G04 ================== begin FILE IDENTIFICATION RECORD ==================*
G04 Layout Name:  DA0T6MTH8C0_t6m_tray_bp_c_brd_103112_274.brd*
G04 Film Name:    pmt*
G04 File Format:  Gerber RS274X*
G04 File Origin:  Cadence Allegro 16.3-S048*
G04 Origin Date:  Tue Nov 26 11:26:41 2013*
G04 *
G04 Layer:  VIA CLASS/PASTEMASK_TOP*
G04 Layer:  PIN/PASTEMASK_TOP*
G04 Layer:  PACKAGE GEOMETRY/PASTEMASK_TOP*
G04 Layer:  MANUFACTURING/PHOTOPLOT_OUTLINE*
G04 Layer:  DRAWING FORMAT/TITLE_BLOCK*
G04 Layer:  DRAWING FORMAT/TITLE_DATA_PMT*
G04 *
G04 Offset:    (0.00 0.00)*
G04 Mirror:    No*
G04 Mode:      Positive*
G04 Rotation:  0*
G04 FullContactRelief:  No*
G04 UndefLineWidth:     6.00*
G04 ================== end FILE IDENTIFICATION RECORD ====================*
%FSLAX25Y25*MOIN*%
%IR0*IPPOS*OFA0.00000B0.00000*MIA0B0*SFA1.00000B1.00000*%
%ADD25C,.03*%
%ADD15C,.04*%
%ADD23C,.051*%
%ADD14C,.054*%
%ADD12C,.063*%
%ADD10C,.066*%
%ADD26R,.051X.051*%
%ADD13R,.063X.063*%
%ADD11R,.066X.066*%
%ADD22O,.02X.08*%
%ADD16R,.02X.018*%
%ADD24C,.12*%
%ADD19R,.018X.02*%
%ADD21R,.04X.071*%
%ADD18R,.028X.032*%
%ADD27R,.015X.073*%
%ADD17R,.054X.044*%
%ADD28R,.103X.189*%
%ADD20R,.044X.054*%
%ADD29C,.006*%
G75*
%LPD*%
G75*
G54D10*
X9088Y80158D03*
Y91958D03*
X109288Y92458D03*
Y103958D03*
G54D20*
X354460Y121642D03*
Y130142D03*
X361940Y121642D03*
Y130142D03*
X618140Y120258D03*
X610660D03*
X618140Y112158D03*
X610660D03*
X1225160Y126242D03*
Y134542D03*
X1232640Y126242D03*
Y134542D03*
X1480760Y117558D03*
Y126358D03*
X1488240Y117558D03*
Y126358D03*
G54D11*
X19088Y80158D03*
Y91958D03*
X119288Y92458D03*
Y103958D03*
G54D21*
X352092Y139282D03*
X351992Y149118D03*
X363509Y139282D03*
X363409Y149118D03*
X621908Y148982D03*
X610491D03*
X622013Y158618D03*
X610596D03*
X1222199Y143895D03*
X1222304Y153605D03*
X1233616Y143895D03*
X1233721Y153605D03*
X1480708Y162291D03*
X1480794Y152600D03*
X1492125Y162291D03*
X1492211Y152600D03*
G54D12*
X44528Y41339D03*
Y53150D03*
X56339Y41339D03*
Y53150D03*
X44528Y64961D03*
Y76772D03*
X56339Y64961D03*
Y76772D03*
X44528Y88583D03*
Y100394D03*
X56339Y88583D03*
Y100394D03*
X44528Y112205D03*
Y124016D03*
X56339Y112205D03*
Y124016D03*
X44528Y135827D03*
G54D22*
X398307Y40511D03*
X396732Y72795D03*
X417205Y40511D03*
X407756D03*
X414055D03*
X410906D03*
X420354D03*
X401457D03*
X404606D03*
X421929Y72795D03*
X418780D03*
X399882D03*
X406181D03*
X415630D03*
X412480D03*
X409331D03*
X403032D03*
X426654Y40511D03*
X423504D03*
X425079Y72795D03*
X557048Y40512D03*
X547599D03*
X560198D03*
X550749D03*
X553898D03*
X546024Y72796D03*
X549174D03*
X555473D03*
X558623D03*
X552324D03*
X575946Y40512D03*
X566497D03*
X563347D03*
X572796D03*
X569646D03*
X574371Y72796D03*
X571221D03*
X568072D03*
X564922D03*
X561772D03*
X1268386Y40512D03*
X1271536D03*
X1274685D03*
X1266811Y72796D03*
X1269961D03*
X1273111D03*
X1296733Y40512D03*
X1287284D03*
X1277835D03*
X1284134D03*
X1280985D03*
X1293583D03*
X1290433D03*
X1295158Y72796D03*
X1292008D03*
X1288859D03*
X1276260D03*
X1285709D03*
X1282559D03*
X1279410D03*
X1427127Y40511D03*
X1417678D03*
X1433426D03*
X1430277D03*
X1420828D03*
X1423977D03*
X1416103Y72795D03*
X1419253D03*
X1425552D03*
X1435001D03*
X1431851D03*
X1428702D03*
X1422403D03*
X1446025Y40511D03*
X1436576D03*
X1442875D03*
X1439725D03*
X1444450Y72795D03*
X1441300D03*
X1438151D03*
G54D13*
X56339Y135827D03*
G54D14*
X81929Y76772D03*
Y68898D03*
X89803Y76772D03*
Y68898D03*
X81929Y100394D03*
Y92520D03*
Y84646D03*
X89803Y100394D03*
Y92520D03*
Y84646D03*
X81929Y108268D03*
X89803D03*
G54D23*
X468859Y115666D03*
Y141650D03*
X488859Y115666D03*
X478859D03*
X483859Y125666D03*
X473859D03*
X478859Y141650D03*
X488859D03*
X473859Y151650D03*
X483859D03*
X498859Y115666D03*
X503859Y125666D03*
X493859D03*
X498859Y141650D03*
X493859Y151650D03*
X1338938Y115666D03*
X1343938Y125666D03*
X1338938Y141650D03*
X1343938Y151650D03*
X1358938Y115666D03*
X1348938D03*
X1363938Y125666D03*
X1353938D03*
X1348938Y141650D03*
X1358938D03*
X1353938Y151650D03*
X1363938D03*
X1368938Y115666D03*
X1373938Y125666D03*
X1368938Y141650D03*
G54D24*
X452875Y131650D03*
X455867Y153658D03*
X452875Y194642D03*
X516851Y140666D03*
X519843Y115666D03*
Y194642D03*
X1322954Y131650D03*
Y194642D03*
X1325946Y153658D03*
X1389922Y115666D03*
X1386930Y140666D03*
X1389922Y194642D03*
G54D15*
X109400Y41000D03*
X1009700Y81500D03*
X1636400Y43200D03*
G54D16*
X101739Y65963D03*
Y62813D03*
X111958Y62925D03*
Y66075D03*
X121958Y62925D03*
Y66075D03*
X116958Y62925D03*
Y66075D03*
X106958Y62925D03*
Y66075D03*
X111958Y76125D03*
X121958D03*
X116958D03*
X106958D03*
X111958Y79275D03*
X121958D03*
X116958D03*
X106958D03*
X358259Y93869D03*
Y90719D03*
X362759Y93869D03*
Y90719D03*
X403600Y9925D03*
Y13075D03*
X408200Y9925D03*
Y13075D03*
X412800Y10025D03*
Y13175D03*
X417200Y10025D03*
Y13175D03*
X477630Y83278D03*
Y86428D03*
X483258Y87208D03*
Y84058D03*
X487558D03*
Y87208D03*
X496242D03*
Y84058D03*
X500558D03*
Y87208D03*
X504842Y84058D03*
Y87208D03*
X571700Y10425D03*
Y13575D03*
X567300Y10425D03*
Y13575D03*
X562800Y10425D03*
Y13575D03*
X576100Y10425D03*
Y13575D03*
X1229324Y93574D03*
Y90424D03*
X1233524Y93574D03*
Y90424D03*
X1272600Y8825D03*
Y11975D03*
X1281600Y8825D03*
Y11975D03*
X1277000Y8825D03*
Y11975D03*
X1286000Y8825D03*
Y11975D03*
X1350257Y84185D03*
Y87335D03*
X1355642Y86908D03*
Y83758D03*
X1359942D03*
Y86908D03*
X1364258Y83692D03*
Y86842D03*
X1345558Y84213D03*
Y87363D03*
X1368658Y86842D03*
Y83692D03*
X1376358Y83313D03*
Y86463D03*
X1433400Y10625D03*
Y13775D03*
X1447000Y10725D03*
Y13875D03*
X1437900Y10625D03*
Y13775D03*
X1442600Y10725D03*
Y13875D03*
G54D25*
X477630Y78800D03*
X487558Y78600D03*
X471787Y78400D03*
X496242Y78600D03*
X504842Y78684D03*
X702610Y53111D03*
X713900Y60500D03*
X707600Y57900D03*
X1341187Y78400D03*
X1348300Y78500D03*
X1357700Y78700D03*
X1364258D03*
X1376358D03*
X1572300Y53500D03*
X1579300Y57900D03*
X1586100Y60500D03*
G54D17*
X332000Y128960D03*
Y136440D03*
X340473Y129060D03*
Y136540D03*
X617949Y131360D03*
Y138840D03*
X626173Y131360D03*
Y138840D03*
X1206000Y128760D03*
Y136240D03*
X1214100Y128860D03*
Y136340D03*
X1495800Y135760D03*
Y143240D03*
X1487600Y135760D03*
Y143240D03*
G54D26*
X503859Y151650D03*
X1373938D03*
G54D27*
X660965Y101968D03*
X664114D03*
X667264D03*
X670414D03*
X673563D03*
X659390Y111850D03*
X662540D03*
X665689D03*
X668839D03*
X671988D03*
X675138D03*
X676713Y101968D03*
X679862D03*
X683012D03*
X686162D03*
X689311D03*
X692461D03*
X695610D03*
X678288Y111850D03*
X681437D03*
X684587D03*
X687736D03*
X690886D03*
X694036D03*
X697185D03*
X698760Y101968D03*
X735807D03*
X738956D03*
X742106D03*
X734232Y111850D03*
X737382D03*
X740531D03*
X743681D03*
X745256Y101968D03*
X748405D03*
X751555D03*
X754704D03*
X757854D03*
X761004D03*
X764153D03*
X767303D03*
X746830Y111850D03*
X749980D03*
X753130D03*
X756279D03*
X759429D03*
X762578D03*
X765728D03*
X770452Y101968D03*
X773602D03*
X768878Y111850D03*
X772027D03*
X1531043Y101968D03*
X1534192D03*
X1537342D03*
X1540492D03*
X1543641D03*
X1546791D03*
X1549940D03*
X1529468Y111850D03*
X1532618D03*
X1535767D03*
X1538917D03*
X1542066D03*
X1545216D03*
X1548366D03*
X1553090Y101968D03*
X1556240D03*
X1559389D03*
X1562539D03*
X1565688D03*
X1568838D03*
X1551515Y111850D03*
X1554665D03*
X1557814D03*
X1560964D03*
X1564114D03*
X1567263D03*
X1605886Y101968D03*
X1609035D03*
X1612185D03*
X1615335D03*
X1618484D03*
X1604311Y111850D03*
X1607461D03*
X1610610D03*
X1613760D03*
X1616909D03*
X1621634Y101968D03*
X1624783D03*
X1627933D03*
X1631083D03*
X1634232D03*
X1637382D03*
X1640531D03*
X1620059Y111850D03*
X1623209D03*
X1626358D03*
X1629508D03*
X1632657D03*
X1635807D03*
X1638957D03*
X1642106D03*
X1643681Y101968D03*
G54D18*
X346524Y90099D03*
Y95899D03*
X352424Y90099D03*
Y95899D03*
X1217324Y89699D03*
Y95499D03*
X1223424D03*
Y89699D03*
G54D28*
X1676417Y114567D03*
G54D19*
X350465Y108561D03*
Y102961D03*
Y114657D03*
X361285Y102961D03*
X364435D03*
X361285Y114657D03*
X364435D03*
X361285Y108561D03*
X364435D03*
X353615D03*
Y102961D03*
Y114657D03*
X460285Y87315D03*
X463435D03*
X460285Y91615D03*
X463435D03*
X460285Y95915D03*
X463435D03*
X460285Y83015D03*
X463435D03*
X460285Y104515D03*
X463435D03*
X460285Y100215D03*
X463435D03*
X474692Y91958D03*
X477842D03*
X471787Y87558D03*
X468637D03*
X471787Y83258D03*
X468637D03*
X513787Y91561D03*
X510637D03*
X513787Y95861D03*
X510637D03*
X510813Y83242D03*
X513963D03*
X510813Y87442D03*
X513963D03*
X513787Y104461D03*
X510637D03*
X513787Y100161D03*
X510637D03*
X611415Y95139D03*
X608265D03*
X611415Y90157D03*
X608265D03*
X619613D03*
X622763D03*
X619613Y95139D03*
X622763D03*
X611415Y105157D03*
X608265D03*
X611415Y100157D03*
X608265D03*
X619613D03*
X622763D03*
X619613Y105157D03*
X622763D03*
X1223263Y108361D03*
X1220113D03*
X1223263Y102861D03*
X1220113D03*
X1223263Y119561D03*
X1220113D03*
X1223263Y114043D03*
X1220113D03*
X1230985Y119561D03*
X1234135D03*
X1230985Y114043D03*
X1234135D03*
X1230985Y108361D03*
X1234135D03*
X1230985Y102861D03*
X1234135D03*
X1329637Y85839D03*
X1332787D03*
X1329637Y90339D03*
X1332787D03*
X1329637Y94639D03*
X1332787D03*
X1329737Y99239D03*
X1332887D03*
X1341187Y83258D03*
X1338037D03*
X1341187Y87558D03*
X1338037D03*
X1384287Y95861D03*
X1381137D03*
X1384163Y91561D03*
X1381013D03*
Y83042D03*
X1384163D03*
X1381013Y87242D03*
X1384163D03*
X1384287Y104461D03*
X1381137D03*
X1384287Y100161D03*
X1381137D03*
X1481215Y93057D03*
X1478065D03*
X1481215Y98057D03*
X1478065D03*
X1481215Y103257D03*
X1478065D03*
X1481215Y109357D03*
X1478065D03*
X1488313Y93057D03*
X1491463D03*
X1488313Y98057D03*
X1491463D03*
X1488313Y103257D03*
X1491463D03*
X1488313Y109357D03*
X1491463D03*
G54D29*
G01X457212Y-338900D02*
Y-343900D01*
G01X455755Y-338900D02*
X458669D01*
G01X463579Y-343900D02*
X461045D01*
Y-338900D01*
X463579D01*
G01X462565Y-341317D02*
X461045D01*
G01X466145Y-338900D02*
Y-343900D01*
X468679D01*
G01X472512Y-344067D02*
X472385Y-343983D01*
Y-343817D01*
X472512Y-343733D01*
X472639Y-343817D01*
Y-343983D01*
X472512Y-344067D01*
G01Y-341817D02*
X472385Y-341733D01*
Y-341567D01*
X472512Y-341483D01*
X472639Y-341567D01*
Y-341733D01*
X472512Y-341817D01*
G01X477295Y-345567D02*
X476662Y-344733D01*
X476345Y-343900D01*
Y-340567D01*
X476662Y-339733D01*
X477295Y-338900D01*
G01X482712D02*
X482205Y-339067D01*
X481825Y-339483D01*
X481572Y-339983D01*
X481382Y-340650D01*
X481319Y-341400D01*
X481382Y-342150D01*
X481572Y-342817D01*
X481825Y-343317D01*
X482205Y-343733D01*
X482712Y-343900D01*
X483219Y-343733D01*
X483599Y-343317D01*
X483852Y-342817D01*
X484042Y-342150D01*
X484105Y-341400D01*
X484042Y-340650D01*
X483852Y-339983D01*
X483599Y-339483D01*
X483219Y-339067D01*
X482712Y-338900D01*
G01X486419Y-342900D02*
X486799Y-343483D01*
X487305Y-343817D01*
X487875Y-343900D01*
X488382Y-343817D01*
X488889Y-343400D01*
X489205Y-342900D01*
X489269Y-342400D01*
X489142Y-341817D01*
X488699Y-341400D01*
X488255Y-341233D01*
X487685D01*
G01X488255D02*
X488635Y-340983D01*
X488952Y-340567D01*
X489079Y-340067D01*
X488952Y-339567D01*
X488635Y-339150D01*
X488065Y-338900D01*
X487495Y-338983D01*
X486925Y-339317D01*
G01X493229Y-345567D02*
X493862Y-344733D01*
X494179Y-343900D01*
Y-340567D01*
X493862Y-339733D01*
X493229Y-338900D01*
G01X496619Y-342900D02*
X496999Y-343483D01*
X497505Y-343817D01*
X498075Y-343900D01*
X498582Y-343817D01*
X499089Y-343400D01*
X499405Y-342900D01*
X499469Y-342400D01*
X499342Y-341817D01*
X498899Y-341400D01*
X498455Y-341233D01*
X497885D01*
G01X498455D02*
X498835Y-340983D01*
X499152Y-340567D01*
X499279Y-340067D01*
X499152Y-339567D01*
X498835Y-339150D01*
X498265Y-338900D01*
X497695Y-338983D01*
X497125Y-339317D01*
G01X501909Y-339733D02*
X502289Y-339233D01*
X502732Y-338983D01*
X503239Y-338900D01*
X503872Y-339067D01*
X504315Y-339483D01*
X504442Y-339983D01*
X504379Y-340483D01*
X504125Y-340900D01*
X502859Y-341733D01*
X502289Y-342317D01*
X501909Y-343150D01*
X501782Y-343900D01*
X504442D01*
G01X508085D02*
X508212Y-342817D01*
X508402Y-341900D01*
X508655Y-341067D01*
X508972Y-340150D01*
X509479Y-338900D01*
X506945D01*
G01X512489Y-342233D02*
X514135D01*
G01X517209Y-339733D02*
X517589Y-339233D01*
X518032Y-338983D01*
X518539Y-338900D01*
X519172Y-339067D01*
X519615Y-339483D01*
X519742Y-339983D01*
X519679Y-340483D01*
X519425Y-340900D01*
X518159Y-341733D01*
X517589Y-342317D01*
X517209Y-343150D01*
X517082Y-343900D01*
X519742D01*
G01X522119Y-342900D02*
X522499Y-343483D01*
X523005Y-343817D01*
X523575Y-343900D01*
X524082Y-343817D01*
X524589Y-343400D01*
X524905Y-342900D01*
X524969Y-342400D01*
X524842Y-341817D01*
X524399Y-341400D01*
X523955Y-341233D01*
X523385D01*
G01X523955D02*
X524335Y-340983D01*
X524652Y-340567D01*
X524779Y-340067D01*
X524652Y-339567D01*
X524335Y-339150D01*
X523765Y-338900D01*
X523195Y-338983D01*
X522625Y-339317D01*
G01X529372Y-343900D02*
Y-338900D01*
X527029Y-342483D01*
X530195D01*
G01X532319Y-343150D02*
X532699Y-343567D01*
X533142Y-343817D01*
X533712Y-343900D01*
X534282Y-343733D01*
X534725Y-343400D01*
X535042Y-342817D01*
X535105Y-342150D01*
X534979Y-341483D01*
X534662Y-341067D01*
X534219Y-340733D01*
X533775Y-340650D01*
X533332Y-340733D01*
X532762Y-341067D01*
X532952Y-338900D01*
X534662D01*
G01X542709Y-343900D02*
Y-338900D01*
X545115D01*
G01X544229Y-341317D02*
X542709D01*
G01X547429Y-343900D02*
X549012Y-338900D01*
X550595Y-343900D01*
G01X550025Y-342150D02*
X547999D01*
G01X552782Y-343900D02*
X555442Y-338900D01*
G01X552782D02*
X555442Y-343900D01*
G01X559212Y-344067D02*
X559085Y-343983D01*
Y-343817D01*
X559212Y-343733D01*
X559339Y-343817D01*
Y-343983D01*
X559212Y-344067D01*
G01Y-341817D02*
X559085Y-341733D01*
Y-341567D01*
X559212Y-341483D01*
X559339Y-341567D01*
Y-341733D01*
X559212Y-341817D01*
G01X563995Y-345567D02*
X563362Y-344733D01*
X563045Y-343900D01*
Y-340567D01*
X563362Y-339733D01*
X563995Y-338900D01*
G01X569412D02*
X568905Y-339067D01*
X568525Y-339483D01*
X568272Y-339983D01*
X568082Y-340650D01*
X568019Y-341400D01*
X568082Y-342150D01*
X568272Y-342817D01*
X568525Y-343317D01*
X568905Y-343733D01*
X569412Y-343900D01*
X569919Y-343733D01*
X570299Y-343317D01*
X570552Y-342817D01*
X570742Y-342150D01*
X570805Y-341400D01*
X570742Y-340650D01*
X570552Y-339983D01*
X570299Y-339483D01*
X569919Y-339067D01*
X569412Y-338900D01*
G01X573119Y-342900D02*
X573499Y-343483D01*
X574005Y-343817D01*
X574575Y-343900D01*
X575082Y-343817D01*
X575589Y-343400D01*
X575905Y-342900D01*
X575969Y-342400D01*
X575842Y-341817D01*
X575399Y-341400D01*
X574955Y-341233D01*
X574385D01*
G01X574955D02*
X575335Y-340983D01*
X575652Y-340567D01*
X575779Y-340067D01*
X575652Y-339567D01*
X575335Y-339150D01*
X574765Y-338900D01*
X574195Y-338983D01*
X573625Y-339317D01*
G01X579929Y-345567D02*
X580562Y-344733D01*
X580879Y-343900D01*
Y-340567D01*
X580562Y-339733D01*
X579929Y-338900D01*
G01X583319Y-342900D02*
X583699Y-343483D01*
X584205Y-343817D01*
X584775Y-343900D01*
X585282Y-343817D01*
X585789Y-343400D01*
X586105Y-342900D01*
X586169Y-342400D01*
X586042Y-341817D01*
X585599Y-341400D01*
X585155Y-341233D01*
X584585D01*
G01X585155D02*
X585535Y-340983D01*
X585852Y-340567D01*
X585979Y-340067D01*
X585852Y-339567D01*
X585535Y-339150D01*
X584965Y-338900D01*
X584395Y-338983D01*
X583825Y-339317D01*
G01X588735Y-343317D02*
X589179Y-343733D01*
X589685Y-343900D01*
X590192Y-343733D01*
X590635Y-343233D01*
X590952Y-342483D01*
X591079Y-341733D01*
Y-340817D01*
X590952Y-340067D01*
X590635Y-339400D01*
X590255Y-339067D01*
X589812Y-338900D01*
X589305Y-339067D01*
X588925Y-339400D01*
X588672Y-339900D01*
X588545Y-340567D01*
X588672Y-341150D01*
X588989Y-341733D01*
X589369Y-342067D01*
X589812Y-342150D01*
X590319Y-341983D01*
X590699Y-341567D01*
X591079Y-340817D01*
G01X594785Y-343900D02*
X594912Y-342817D01*
X595102Y-341900D01*
X595355Y-341067D01*
X595672Y-340150D01*
X596179Y-338900D01*
X593645D01*
G01X599189Y-342233D02*
X600835D01*
G01X603719Y-342900D02*
X604099Y-343483D01*
X604605Y-343817D01*
X605175Y-343900D01*
X605682Y-343817D01*
X606189Y-343400D01*
X606505Y-342900D01*
X606569Y-342400D01*
X606442Y-341817D01*
X605999Y-341400D01*
X605555Y-341233D01*
X604985D01*
G01X605555D02*
X605935Y-340983D01*
X606252Y-340567D01*
X606379Y-340067D01*
X606252Y-339567D01*
X605935Y-339150D01*
X605365Y-338900D01*
X604795Y-338983D01*
X604225Y-339317D01*
G01X609009Y-341817D02*
X609452Y-341233D01*
X609832Y-340900D01*
X610339Y-340733D01*
X610782Y-340900D01*
X611099Y-341233D01*
X611352Y-341733D01*
X611415Y-342317D01*
X611352Y-342817D01*
X611099Y-343317D01*
X610719Y-343733D01*
X610275Y-343900D01*
X609769Y-343733D01*
X609325Y-343233D01*
X609072Y-342483D01*
X609009Y-341650D01*
X609135Y-340567D01*
X609325Y-339983D01*
X609642Y-339400D01*
X610085Y-338983D01*
X610529Y-338900D01*
X610972Y-339067D01*
X611289Y-339483D01*
G01X615312Y-343900D02*
Y-338900D01*
X614552Y-339900D01*
G01Y-343900D02*
X616072D01*
G01X621172D02*
Y-338900D01*
X618829Y-342483D01*
X621995D01*
G01X445212Y-273900D02*
Y-348900D01*
X945212D01*
Y-273900D01*
X445212D01*
G01X640212D02*
Y-348900D01*
G01Y-323900D02*
X743212D01*
Y-298900D01*
G01X640212D02*
X743212D01*
G01Y-273900D02*
Y-348900D01*
G01X745212Y-273900D02*
Y-348900D01*
G01X750719Y-333900D02*
Y-328900D01*
X751985D01*
X752492Y-329150D01*
X752872Y-329483D01*
X753189Y-329983D01*
X753442Y-330567D01*
X753505Y-331400D01*
X753442Y-332233D01*
X753189Y-332817D01*
X752872Y-333317D01*
X752492Y-333650D01*
X751985Y-333900D01*
X750719D01*
G01X755629D02*
X757212Y-328900D01*
X758795Y-333900D01*
G01X758225Y-332150D02*
X756199D01*
G01X762312Y-328900D02*
Y-333900D01*
G01X760855Y-328900D02*
X763769D01*
G01X768679Y-333900D02*
X766145D01*
Y-328900D01*
X768679D01*
G01X767665Y-331317D02*
X766145D01*
G01X772512Y-334067D02*
X772385Y-333983D01*
Y-333817D01*
X772512Y-333733D01*
X772639Y-333817D01*
Y-333983D01*
X772512Y-334067D01*
G01Y-331817D02*
X772385Y-331733D01*
Y-331567D01*
X772512Y-331483D01*
X772639Y-331567D01*
Y-331733D01*
X772512Y-331817D01*
G01X745212Y-323900D02*
X945212D01*
G01X750845Y-308900D02*
Y-303900D01*
X752365D01*
X752872Y-304150D01*
X753252Y-304733D01*
X753379Y-305400D01*
X753252Y-306067D01*
X752935Y-306567D01*
X752365Y-306817D01*
X750845D01*
G01X756072Y-309067D02*
X758352Y-303900D01*
G01X760855Y-308900D02*
Y-303900D01*
X763769Y-308900D01*
Y-303900D01*
G01X767412Y-309067D02*
X767285Y-308983D01*
Y-308817D01*
X767412Y-308733D01*
X767539Y-308817D01*
Y-308983D01*
X767412Y-309067D01*
G01Y-306817D02*
X767285Y-306733D01*
Y-306567D01*
X767412Y-306483D01*
X767539Y-306567D01*
Y-306733D01*
X767412Y-306817D01*
G01X745212Y-298900D02*
X945212D01*
G01X750845Y-283900D02*
Y-278900D01*
X752365D01*
X752872Y-279150D01*
X753252Y-279733D01*
X753379Y-280400D01*
X753252Y-281067D01*
X752935Y-281567D01*
X752365Y-281817D01*
X750845D01*
G01X755945Y-283900D02*
Y-278900D01*
X757529D01*
X758035Y-279150D01*
X758352Y-279483D01*
X758479Y-280150D01*
X758352Y-280817D01*
X757972Y-281233D01*
X757529Y-281483D01*
X755945D01*
G01X757529D02*
X758479Y-283900D01*
G01X762312D02*
X761805Y-283817D01*
X761362Y-283483D01*
X760982Y-282983D01*
X760729Y-282400D01*
X760602Y-281733D01*
Y-281067D01*
X760729Y-280400D01*
X760982Y-279817D01*
X761362Y-279317D01*
X761805Y-278983D01*
X762312Y-278900D01*
X762819Y-278983D01*
X763262Y-279317D01*
X763642Y-279817D01*
X763895Y-280400D01*
X764022Y-281067D01*
Y-281733D01*
X763895Y-282400D01*
X763642Y-282983D01*
X763262Y-283483D01*
X762819Y-283817D01*
X762312Y-283900D01*
G01X766145Y-282900D02*
X766462Y-283400D01*
X766842Y-283733D01*
X767285Y-283900D01*
X767792Y-283733D01*
X768172Y-283400D01*
X768552Y-282900D01*
X768679Y-282233D01*
Y-278900D01*
G01X773779Y-283900D02*
X771245D01*
Y-278900D01*
X773779D01*
G01X772765Y-281317D02*
X771245D01*
G01X779005Y-279317D02*
X778625Y-279067D01*
X778182Y-278900D01*
X777675D01*
X777105Y-279150D01*
X776662Y-279567D01*
X776345Y-280067D01*
X776092Y-280900D01*
X776029Y-281650D01*
X776155Y-282400D01*
X776345Y-282900D01*
X776725Y-283400D01*
X777169Y-283733D01*
X777612Y-283900D01*
X778055D01*
X778499Y-283733D01*
X778879Y-283483D01*
X779195Y-283150D01*
G01X782712Y-278900D02*
Y-283900D01*
G01X781255Y-278900D02*
X784169D01*
G01X787812Y-284067D02*
X787685Y-283983D01*
Y-283817D01*
X787812Y-283733D01*
X787939Y-283817D01*
Y-283983D01*
X787812Y-284067D01*
G01Y-281817D02*
X787685Y-281733D01*
Y-281567D01*
X787812Y-281483D01*
X787939Y-281567D01*
Y-281733D01*
X787812Y-281817D01*
G01X860212Y-323900D02*
Y-348900D01*
G01X865845Y-333900D02*
Y-328900D01*
X867429D01*
X867935Y-329150D01*
X868252Y-329483D01*
X868379Y-330150D01*
X868252Y-330817D01*
X867872Y-331233D01*
X867429Y-331483D01*
X865845D01*
G01X867429D02*
X868379Y-333900D01*
G01X873479D02*
X870945D01*
Y-328900D01*
X873479D01*
G01X872465Y-331317D02*
X870945D01*
G01X875729Y-328900D02*
X877312Y-333900D01*
X878895Y-328900D01*
G01X882412Y-334067D02*
X882285Y-333983D01*
Y-333817D01*
X882412Y-333733D01*
X882539Y-333817D01*
Y-333983D01*
X882412Y-334067D01*
G01Y-331817D02*
X882285Y-331733D01*
Y-331567D01*
X882412Y-331483D01*
X882539Y-331567D01*
Y-331733D01*
X882412Y-331817D01*
G01X909212Y-323900D02*
Y-348900D01*
G01X-471400Y-391900D02*
Y1528800D01*
X2244200D01*
Y-391900D01*
X-471400D01*
G01X455917Y-335560D02*
X456544Y-336085D01*
X457249Y-336400D01*
X457875D01*
X458502Y-336085D01*
X458972Y-335560D01*
X459207Y-334825D01*
X459050Y-334090D01*
X458659Y-333460D01*
X457954Y-333040D01*
X457014Y-332830D01*
X456465Y-332410D01*
X456230Y-331675D01*
X456387Y-330940D01*
X456779Y-330415D01*
X457327Y-330100D01*
X457875D01*
X458424Y-330310D01*
X458894Y-330835D01*
G01X462217Y-336400D02*
Y-330100D01*
G01X465507D02*
Y-336400D01*
G01Y-333250D02*
X462217D01*
G01X469222Y-330100D02*
X471102D01*
G01X470162D02*
Y-336400D01*
G01X469222D02*
X471102D01*
G01X478029D02*
X474895D01*
Y-330100D01*
X478029D01*
G01X476775Y-333145D02*
X474895D01*
G01X480960Y-336400D02*
Y-330100D01*
X484564Y-336400D01*
Y-330100D01*
G01X488905Y-337555D02*
X489219Y-336190D01*
G01X495362Y-330100D02*
Y-336400D01*
G01X493560Y-330100D02*
X497164D01*
G01X499704Y-336400D02*
X501662Y-330100D01*
X503620Y-336400D01*
G01X502915Y-334195D02*
X500409D01*
G01X507022Y-330100D02*
X508902D01*
G01X507962D02*
Y-336400D01*
G01X507022D02*
X508902D01*
G01X511912Y-330100D02*
X513009Y-336400D01*
X514262Y-330100D01*
X515515Y-336400D01*
X516612Y-330100D01*
G01X518604Y-336400D02*
X520562Y-330100D01*
X522520Y-336400D01*
G01X521815Y-334195D02*
X519309D01*
G01X525060Y-336400D02*
Y-330100D01*
X528664Y-336400D01*
Y-330100D01*
G01X537895Y-336400D02*
Y-330100D01*
X539854D01*
X540480Y-330415D01*
X540872Y-330835D01*
X541029Y-331675D01*
X540872Y-332515D01*
X540402Y-333040D01*
X539854Y-333355D01*
X537895D01*
G01X539854D02*
X541029Y-336400D01*
G01X545762Y-336610D02*
X545605Y-336505D01*
Y-336295D01*
X545762Y-336190D01*
X545919Y-336295D01*
Y-336505D01*
X545762Y-336610D01*
G01X552062Y-336400D02*
X551435Y-336295D01*
X550887Y-335875D01*
X550417Y-335245D01*
X550104Y-334510D01*
X549947Y-333670D01*
Y-332830D01*
X550104Y-331990D01*
X550417Y-331255D01*
X550887Y-330625D01*
X551435Y-330205D01*
X552062Y-330100D01*
X552689Y-330205D01*
X553237Y-330625D01*
X553707Y-331255D01*
X554020Y-331990D01*
X554177Y-332830D01*
Y-333670D01*
X554020Y-334510D01*
X553707Y-335245D01*
X553237Y-335875D01*
X552689Y-336295D01*
X552062Y-336400D01*
G01X558362Y-336610D02*
X558205Y-336505D01*
Y-336295D01*
X558362Y-336190D01*
X558519Y-336295D01*
Y-336505D01*
X558362Y-336610D01*
G01X566385Y-330625D02*
X565915Y-330310D01*
X565367Y-330100D01*
X564740D01*
X564035Y-330415D01*
X563487Y-330940D01*
X563095Y-331570D01*
X562782Y-332620D01*
X562704Y-333565D01*
X562860Y-334510D01*
X563095Y-335140D01*
X563565Y-335770D01*
X564114Y-336190D01*
X564662Y-336400D01*
X565210D01*
X565759Y-336190D01*
X566229Y-335875D01*
X566620Y-335455D01*
G01X570962Y-336610D02*
X570805Y-336505D01*
Y-336295D01*
X570962Y-336190D01*
X571119Y-336295D01*
Y-336505D01*
X570962Y-336610D01*
G01X455839Y-326400D02*
Y-320100D01*
G01X458815D02*
X455839Y-323985D01*
G01X459285Y-326400D02*
X457170Y-322200D01*
G01X462139Y-320100D02*
Y-324615D01*
X462452Y-325560D01*
X463079Y-326190D01*
X463862Y-326400D01*
X464645Y-326190D01*
X465272Y-325560D01*
X465585Y-324615D01*
Y-320100D01*
G01X471729Y-326400D02*
X468595D01*
Y-320100D01*
X471729D01*
G01X470475Y-323145D02*
X468595D01*
G01X475522Y-320100D02*
X477402D01*
G01X476462D02*
Y-326400D01*
G01X475522D02*
X477402D01*
G01X487417Y-325560D02*
X488044Y-326085D01*
X488749Y-326400D01*
X489375D01*
X490002Y-326085D01*
X490472Y-325560D01*
X490707Y-324825D01*
X490550Y-324090D01*
X490159Y-323460D01*
X489454Y-323040D01*
X488514Y-322830D01*
X487965Y-322410D01*
X487730Y-321675D01*
X487887Y-320940D01*
X488279Y-320415D01*
X488827Y-320100D01*
X489375D01*
X489924Y-320310D01*
X490394Y-320835D01*
G01X493717Y-326400D02*
Y-320100D01*
G01X497007D02*
Y-326400D01*
G01Y-323250D02*
X493717D01*
G01X499704Y-326400D02*
X501662Y-320100D01*
X503620Y-326400D01*
G01X502915Y-324195D02*
X500409D01*
G01X506160Y-326400D02*
Y-320100D01*
X509764Y-326400D01*
Y-320100D01*
G01X518917Y-326400D02*
Y-320100D01*
G01X522207D02*
Y-326400D01*
G01Y-323250D02*
X518917D01*
G01X525217Y-325560D02*
X525844Y-326085D01*
X526549Y-326400D01*
X527175D01*
X527802Y-326085D01*
X528272Y-325560D01*
X528507Y-324825D01*
X528350Y-324090D01*
X527959Y-323460D01*
X527254Y-323040D01*
X526314Y-322830D01*
X525765Y-322410D01*
X525530Y-321675D01*
X525687Y-320940D01*
X526079Y-320415D01*
X526627Y-320100D01*
X527175D01*
X527724Y-320310D01*
X528194Y-320835D01*
G01X532222Y-320100D02*
X534102D01*
G01X533162D02*
Y-326400D01*
G01X532222D02*
X534102D01*
G01X537504D02*
X539462Y-320100D01*
X541420Y-326400D01*
G01X540715Y-324195D02*
X538209D01*
G01X543960Y-326400D02*
Y-320100D01*
X547564Y-326400D01*
Y-320100D01*
G01X552532Y-323250D02*
X554099D01*
Y-325140D01*
X553629Y-325770D01*
X553080Y-326190D01*
X552297Y-326400D01*
X551514Y-326190D01*
X550965Y-325770D01*
X550495Y-325140D01*
X550182Y-324405D01*
X550025Y-323565D01*
Y-322830D01*
X550182Y-322200D01*
X550495Y-321465D01*
X550965Y-320835D01*
X551435Y-320415D01*
X552062Y-320100D01*
X552610D01*
X553237Y-320310D01*
X553707Y-320730D01*
G01X558205Y-327555D02*
X558519Y-326190D01*
G01X564662Y-320100D02*
Y-326400D01*
G01X562860Y-320100D02*
X566464D01*
G01X569004Y-326400D02*
X570962Y-320100D01*
X572920Y-326400D01*
G01X572215Y-324195D02*
X569709D01*
G01X577262Y-326400D02*
X576635Y-326295D01*
X576087Y-325875D01*
X575617Y-325245D01*
X575304Y-324510D01*
X575147Y-323670D01*
Y-322830D01*
X575304Y-321990D01*
X575617Y-321255D01*
X576087Y-320625D01*
X576635Y-320205D01*
X577262Y-320100D01*
X577889Y-320205D01*
X578437Y-320625D01*
X578907Y-321255D01*
X579220Y-321990D01*
X579377Y-322830D01*
Y-323670D01*
X579220Y-324510D01*
X578907Y-325245D01*
X578437Y-325875D01*
X577889Y-326295D01*
X577262Y-326400D01*
G01X589862D02*
Y-323565D01*
X588295Y-320100D01*
G01X591429D02*
X589862Y-323565D01*
G01X594439Y-320100D02*
Y-324615D01*
X594752Y-325560D01*
X595379Y-326190D01*
X596162Y-326400D01*
X596945Y-326190D01*
X597572Y-325560D01*
X597885Y-324615D01*
Y-320100D01*
G01X600504Y-326400D02*
X602462Y-320100D01*
X604420Y-326400D01*
G01X603715Y-324195D02*
X601209D01*
G01X606960Y-326400D02*
Y-320100D01*
X610564Y-326400D01*
Y-320100D01*
G01X455760Y-316400D02*
Y-310100D01*
X459364Y-316400D01*
Y-310100D01*
G01X463862Y-316400D02*
X463235Y-316295D01*
X462687Y-315875D01*
X462217Y-315245D01*
X461904Y-314510D01*
X461747Y-313670D01*
Y-312830D01*
X461904Y-311990D01*
X462217Y-311255D01*
X462687Y-310625D01*
X463235Y-310205D01*
X463862Y-310100D01*
X464489Y-310205D01*
X465037Y-310625D01*
X465507Y-311255D01*
X465820Y-311990D01*
X465977Y-312830D01*
Y-313670D01*
X465820Y-314510D01*
X465507Y-315245D01*
X465037Y-315875D01*
X464489Y-316295D01*
X463862Y-316400D01*
G01X470162Y-316610D02*
X470005Y-316505D01*
Y-316295D01*
X470162Y-316190D01*
X470319Y-316295D01*
Y-316505D01*
X470162Y-316610D01*
G01X476462Y-316400D02*
Y-310100D01*
X475522Y-311360D01*
G01Y-316400D02*
X477402D01*
G01X482762D02*
X483310Y-316295D01*
X483937Y-315980D01*
X484329Y-315455D01*
X484485Y-314720D01*
X484329Y-313985D01*
X483859Y-313355D01*
X483154Y-313040D01*
X482370D01*
X481900Y-312830D01*
X481509Y-312305D01*
X481352Y-311570D01*
X481587Y-310835D01*
X482135Y-310310D01*
X482762Y-310100D01*
X483389Y-310310D01*
X483937Y-310835D01*
X484172Y-311570D01*
X484015Y-312305D01*
X483624Y-312830D01*
X483154Y-313040D01*
X482370D01*
X481665Y-313355D01*
X481195Y-313985D01*
X481039Y-314720D01*
X481195Y-315455D01*
X481587Y-315980D01*
X482214Y-316295D01*
X482762Y-316400D01*
G01X489062D02*
X489610Y-316295D01*
X490237Y-315980D01*
X490629Y-315455D01*
X490785Y-314720D01*
X490629Y-313985D01*
X490159Y-313355D01*
X489454Y-313040D01*
X488670D01*
X488200Y-312830D01*
X487809Y-312305D01*
X487652Y-311570D01*
X487887Y-310835D01*
X488435Y-310310D01*
X489062Y-310100D01*
X489689Y-310310D01*
X490237Y-310835D01*
X490472Y-311570D01*
X490315Y-312305D01*
X489924Y-312830D01*
X489454Y-313040D01*
X488670D01*
X487965Y-313355D01*
X487495Y-313985D01*
X487339Y-314720D01*
X487495Y-315455D01*
X487887Y-315980D01*
X488514Y-316295D01*
X489062Y-316400D01*
G01X495205Y-317555D02*
X495519Y-316190D01*
G01X499312Y-310100D02*
X500409Y-316400D01*
X501662Y-310100D01*
X502915Y-316400D01*
X504012Y-310100D01*
G01X509529Y-316400D02*
X506395D01*
Y-310100D01*
X509529D01*
G01X508275Y-313145D02*
X506395D01*
G01X512460Y-316400D02*
Y-310100D01*
X516064Y-316400D01*
Y-310100D01*
G01X525217Y-316400D02*
Y-310100D01*
G01X528507D02*
Y-316400D01*
G01Y-313250D02*
X525217D01*
G01X530812Y-310100D02*
X531909Y-316400D01*
X533162Y-310100D01*
X534415Y-316400D01*
X535512Y-310100D01*
G01X537504Y-316400D02*
X539462Y-310100D01*
X541420Y-316400D01*
G01X540715Y-314195D02*
X538209D01*
G01X550574Y-311150D02*
X551044Y-310520D01*
X551592Y-310205D01*
X552219Y-310100D01*
X553002Y-310310D01*
X553550Y-310835D01*
X553707Y-311465D01*
X553629Y-312095D01*
X553315Y-312620D01*
X551749Y-313670D01*
X551044Y-314405D01*
X550574Y-315455D01*
X550417Y-316400D01*
X553707D01*
G01X556560D02*
Y-310100D01*
X560164Y-316400D01*
Y-310100D01*
G01X562939Y-316400D02*
Y-310100D01*
X564505D01*
X565132Y-310415D01*
X565602Y-310835D01*
X565994Y-311465D01*
X566307Y-312200D01*
X566385Y-313250D01*
X566307Y-314300D01*
X565994Y-315035D01*
X565602Y-315665D01*
X565132Y-316085D01*
X564505Y-316400D01*
X562939D01*
G01X575695D02*
Y-310100D01*
X577654D01*
X578280Y-310415D01*
X578672Y-310835D01*
X578829Y-311675D01*
X578672Y-312515D01*
X578202Y-313040D01*
X577654Y-313355D01*
X575695D01*
G01X577654D02*
X578829Y-316400D01*
G01X581839D02*
Y-310100D01*
X583405D01*
X584032Y-310415D01*
X584502Y-310835D01*
X584894Y-311465D01*
X585207Y-312200D01*
X585285Y-313250D01*
X585207Y-314300D01*
X584894Y-315035D01*
X584502Y-315665D01*
X584032Y-316085D01*
X583405Y-316400D01*
X581839D01*
G01X589862Y-316610D02*
X589705Y-316505D01*
Y-316295D01*
X589862Y-316190D01*
X590019Y-316295D01*
Y-316505D01*
X589862Y-316610D01*
G01X479862Y-303700D02*
X477342Y-303283D01*
X475137Y-301617D01*
X473247Y-299117D01*
X471987Y-296200D01*
X471357Y-292867D01*
Y-289533D01*
X471987Y-286200D01*
X473247Y-283283D01*
X475137Y-280784D01*
X477342Y-279117D01*
X479862Y-278700D01*
X482382Y-279117D01*
X484587Y-280784D01*
X486477Y-283283D01*
X487737Y-286200D01*
X488367Y-289533D01*
Y-292867D01*
X487737Y-296200D01*
X486477Y-299117D01*
X484587Y-301617D01*
X482382Y-303283D01*
X479862Y-303700D01*
G01X482382Y-297033D02*
X486162Y-303700D01*
G01X499707Y-287034D02*
Y-298700D01*
X500967Y-301617D01*
X502857Y-303283D01*
X505062Y-303700D01*
X507267Y-303283D01*
X509157Y-301617D01*
X510417Y-298700D01*
G01Y-303700D02*
Y-287034D01*
G01X535932Y-303700D02*
Y-287034D01*
G01Y-289950D02*
X534672Y-288284D01*
X532782Y-287450D01*
X530577Y-287034D01*
X528372Y-287867D01*
X526482Y-289533D01*
X525222Y-292034D01*
X524592Y-295367D01*
X525222Y-298700D01*
X526482Y-301201D01*
X528372Y-302867D01*
X530577Y-303700D01*
X532782Y-303283D01*
X534672Y-302034D01*
X535932Y-300367D01*
G01X550107Y-303700D02*
Y-287034D01*
G01Y-291200D02*
X551367Y-289117D01*
X553257Y-287450D01*
X555777Y-287034D01*
X557982Y-287450D01*
X559872Y-289117D01*
X560817Y-292034D01*
Y-303700D01*
G01X580662Y-278700D02*
Y-303700D01*
G01X576252Y-287034D02*
X585072D01*
G01X611532Y-303700D02*
Y-287034D01*
G01Y-289950D02*
X610272Y-288284D01*
X608382Y-287450D01*
X606177Y-287034D01*
X603972Y-287867D01*
X602082Y-289533D01*
X600822Y-292034D01*
X600192Y-295367D01*
X600822Y-298700D01*
X602082Y-301201D01*
X603972Y-302867D01*
X606177Y-303700D01*
X608382Y-303283D01*
X610272Y-302034D01*
X611532Y-300367D01*
G01X651212Y-283400D02*
Y-291400D01*
X655212D01*
G01X663012D02*
Y-286067D01*
G01Y-287000D02*
X662612Y-286467D01*
X662012Y-286200D01*
X661312Y-286067D01*
X660612Y-286333D01*
X660012Y-286867D01*
X659612Y-287667D01*
X659412Y-288733D01*
X659612Y-289800D01*
X660012Y-290600D01*
X660612Y-291133D01*
X661312Y-291400D01*
X662012Y-291267D01*
X662612Y-290867D01*
X663012Y-290334D01*
G01X667112Y-293800D02*
X667712Y-294067D01*
X668512Y-293800D01*
X669012Y-293267D01*
X669412Y-292600D01*
X670012Y-290467D01*
X671312Y-286067D01*
G01X668112D02*
X670012Y-290467D01*
G01X675712Y-287800D02*
X678912D01*
X678612Y-286867D01*
X678112Y-286333D01*
X677412Y-286067D01*
X676712Y-286200D01*
X676112Y-286600D01*
X675712Y-287533D01*
X675512Y-288334D01*
Y-289133D01*
X675712Y-289933D01*
X676212Y-290733D01*
X676812Y-291267D01*
X677512Y-291400D01*
X678212Y-291133D01*
X678912Y-290334D01*
G01X683812Y-291400D02*
Y-286067D01*
G01Y-287133D02*
X684312Y-286600D01*
X684812Y-286200D01*
X685512Y-286067D01*
X686012Y-286200D01*
X686612Y-286600D01*
G01X673512Y-333400D02*
X675912D01*
G01X674712D02*
Y-341400D01*
G01X673512D02*
X675912D01*
G01X681312D02*
Y-336067D01*
G01Y-337133D02*
X681812Y-336600D01*
X682312Y-336200D01*
X683012Y-336067D01*
X683512Y-336200D01*
X684112Y-336600D01*
G01X689212Y-337800D02*
X692412D01*
X692112Y-336867D01*
X691612Y-336333D01*
X690912Y-336067D01*
X690212Y-336200D01*
X689612Y-336600D01*
X689212Y-337533D01*
X689012Y-338334D01*
Y-339133D01*
X689212Y-339933D01*
X689712Y-340733D01*
X690312Y-341267D01*
X691012Y-341400D01*
X691712Y-341133D01*
X692412Y-340334D01*
G01X697012Y-341400D02*
Y-336067D01*
G01Y-337400D02*
X697412Y-336733D01*
X698012Y-336200D01*
X698812Y-336067D01*
X699512Y-336200D01*
X700112Y-336733D01*
X700412Y-337667D01*
Y-341400D01*
G01X705212Y-337800D02*
X708412D01*
X708112Y-336867D01*
X707612Y-336333D01*
X706912Y-336067D01*
X706212Y-336200D01*
X705612Y-336600D01*
X705212Y-337533D01*
X705012Y-338334D01*
Y-339133D01*
X705212Y-339933D01*
X705712Y-340733D01*
X706312Y-341267D01*
X707012Y-341400D01*
X707712Y-341133D01*
X708412Y-340334D01*
G01X662712Y-316400D02*
Y-308400D01*
X665112D01*
X665912Y-308800D01*
X666512Y-309733D01*
X666712Y-310800D01*
X666512Y-311867D01*
X666012Y-312667D01*
X665112Y-313067D01*
X662712D01*
G01X670212Y-316400D02*
X672712Y-308400D01*
X675212Y-316400D01*
G01X674312Y-313600D02*
X671112D01*
G01X678612Y-315334D02*
X679412Y-316000D01*
X680312Y-316400D01*
X681112D01*
X681912Y-316000D01*
X682512Y-315334D01*
X682812Y-314400D01*
X682612Y-313467D01*
X682112Y-312667D01*
X681212Y-312133D01*
X680012Y-311867D01*
X679312Y-311333D01*
X679012Y-310400D01*
X679212Y-309467D01*
X679712Y-308800D01*
X680412Y-308400D01*
X681112D01*
X681812Y-308667D01*
X682412Y-309333D01*
G01X688712Y-308400D02*
Y-316400D01*
G01X686412Y-308400D02*
X691012D01*
G01X695412Y-313733D02*
X698012D01*
G01X704712Y-308400D02*
Y-316400D01*
G01X702412Y-308400D02*
X707012D01*
G01X712712Y-316400D02*
X711912Y-316267D01*
X711212Y-315733D01*
X710612Y-314933D01*
X710212Y-314000D01*
X710012Y-312933D01*
Y-311867D01*
X710212Y-310800D01*
X710612Y-309867D01*
X711212Y-309067D01*
X711912Y-308533D01*
X712712Y-308400D01*
X713512Y-308533D01*
X714212Y-309067D01*
X714812Y-309867D01*
X715212Y-310800D01*
X715412Y-311867D01*
Y-312933D01*
X715212Y-314000D01*
X714812Y-314933D01*
X714212Y-315733D01*
X713512Y-316267D01*
X712712Y-316400D01*
G01X718712D02*
Y-308400D01*
X721112D01*
X721912Y-308800D01*
X722512Y-309733D01*
X722712Y-310800D01*
X722512Y-311867D01*
X722012Y-312667D01*
X721112Y-313067D01*
X718712D01*
G01X777812Y-334733D02*
X778412Y-333933D01*
X779112Y-333533D01*
X779912Y-333400D01*
X780912Y-333667D01*
X781612Y-334333D01*
X781812Y-335133D01*
X781712Y-335934D01*
X781312Y-336600D01*
X779312Y-337933D01*
X778412Y-338867D01*
X777812Y-340200D01*
X777612Y-341400D01*
X781812D01*
G01X787712Y-333400D02*
X786912Y-333667D01*
X786312Y-334333D01*
X785912Y-335133D01*
X785612Y-336200D01*
X785512Y-337400D01*
X785612Y-338600D01*
X785912Y-339667D01*
X786312Y-340467D01*
X786912Y-341133D01*
X787712Y-341400D01*
X788512Y-341133D01*
X789112Y-340467D01*
X789512Y-339667D01*
X789812Y-338600D01*
X789912Y-337400D01*
X789812Y-336200D01*
X789512Y-335133D01*
X789112Y-334333D01*
X788512Y-333667D01*
X787712Y-333400D01*
G01X795712Y-341400D02*
Y-333400D01*
X794512Y-335000D01*
G01Y-341400D02*
X796912D01*
G01X801812Y-334733D02*
X802412Y-333933D01*
X803112Y-333533D01*
X803912Y-333400D01*
X804912Y-333667D01*
X805612Y-334333D01*
X805812Y-335133D01*
X805712Y-335934D01*
X805312Y-336600D01*
X803312Y-337933D01*
X802412Y-338867D01*
X801812Y-340200D01*
X801612Y-341400D01*
X805812D01*
G01X809912Y-341667D02*
X813512Y-333400D01*
G01X819712Y-341400D02*
Y-333400D01*
X818512Y-335000D01*
G01Y-341400D02*
X820912D01*
G01X827712Y-333400D02*
X826912Y-333667D01*
X826312Y-334333D01*
X825912Y-335133D01*
X825612Y-336200D01*
X825512Y-337400D01*
X825612Y-338600D01*
X825912Y-339667D01*
X826312Y-340467D01*
X826912Y-341133D01*
X827712Y-341400D01*
X828512Y-341133D01*
X829112Y-340467D01*
X829512Y-339667D01*
X829812Y-338600D01*
X829912Y-337400D01*
X829812Y-336200D01*
X829512Y-335133D01*
X829112Y-334333D01*
X828512Y-333667D01*
X827712Y-333400D01*
G01X833912Y-341667D02*
X837512Y-333400D01*
G01X841512Y-339800D02*
X842112Y-340733D01*
X842912Y-341267D01*
X843812Y-341400D01*
X844612Y-341267D01*
X845412Y-340600D01*
X845912Y-339800D01*
X846012Y-339000D01*
X845812Y-338067D01*
X845112Y-337400D01*
X844412Y-337133D01*
X843512D01*
G01X844412D02*
X845012Y-336733D01*
X845512Y-336067D01*
X845712Y-335267D01*
X845512Y-334467D01*
X845012Y-333800D01*
X844112Y-333400D01*
X843212Y-333533D01*
X842312Y-334067D01*
G01X851712Y-341400D02*
Y-333400D01*
X850512Y-335000D01*
G01Y-341400D02*
X852912D01*
G01X777512Y-316400D02*
Y-308400D01*
X779512D01*
X780312Y-308800D01*
X780912Y-309333D01*
X781412Y-310133D01*
X781812Y-311067D01*
X781912Y-312400D01*
X781812Y-313733D01*
X781412Y-314667D01*
X780912Y-315467D01*
X780312Y-316000D01*
X779512Y-316400D01*
X777512D01*
G01X785212D02*
X787712Y-308400D01*
X790212Y-316400D01*
G01X789312Y-313600D02*
X786112D01*
G01X795712Y-308400D02*
X794912Y-308667D01*
X794312Y-309333D01*
X793912Y-310133D01*
X793612Y-311200D01*
X793512Y-312400D01*
X793612Y-313600D01*
X793912Y-314667D01*
X794312Y-315467D01*
X794912Y-316133D01*
X795712Y-316400D01*
X796512Y-316133D01*
X797112Y-315467D01*
X797512Y-314667D01*
X797812Y-313600D01*
X797912Y-312400D01*
X797812Y-311200D01*
X797512Y-310133D01*
X797112Y-309333D01*
X796512Y-308667D01*
X795712Y-308400D01*
G01X803712D02*
Y-316400D01*
G01X801412Y-308400D02*
X806012D01*
G01X809812Y-313067D02*
X810512Y-312133D01*
X811112Y-311600D01*
X811912Y-311333D01*
X812612Y-311600D01*
X813112Y-312133D01*
X813512Y-312933D01*
X813612Y-313867D01*
X813512Y-314667D01*
X813112Y-315467D01*
X812512Y-316133D01*
X811812Y-316400D01*
X811012Y-316133D01*
X810312Y-315334D01*
X809912Y-314133D01*
X809812Y-312800D01*
X810012Y-311067D01*
X810312Y-310133D01*
X810812Y-309200D01*
X811512Y-308533D01*
X812212Y-308400D01*
X812912Y-308667D01*
X813412Y-309333D01*
G01X817112Y-316400D02*
Y-308400D01*
X819712Y-315067D01*
X822312Y-308400D01*
Y-316400D01*
G01X827712Y-308400D02*
Y-316400D01*
G01X825412Y-308400D02*
X830012D01*
G01X833612Y-316400D02*
Y-308400D01*
G01X837812D02*
Y-316400D01*
G01Y-312400D02*
X833612D01*
G01X843712Y-316400D02*
X844412Y-316267D01*
X845212Y-315867D01*
X845712Y-315200D01*
X845912Y-314267D01*
X845712Y-313334D01*
X845112Y-312533D01*
X844212Y-312133D01*
X843212D01*
X842612Y-311867D01*
X842112Y-311200D01*
X841912Y-310267D01*
X842212Y-309333D01*
X842912Y-308667D01*
X843712Y-308400D01*
X844512Y-308667D01*
X845212Y-309333D01*
X845512Y-310267D01*
X845312Y-311200D01*
X844812Y-311867D01*
X844212Y-312133D01*
X843212D01*
X842312Y-312533D01*
X841712Y-313334D01*
X841512Y-314267D01*
X841712Y-315200D01*
X842212Y-315867D01*
X843012Y-316267D01*
X843712Y-316400D01*
G01X853912Y-309067D02*
X853312Y-308667D01*
X852612Y-308400D01*
X851812D01*
X850912Y-308800D01*
X850212Y-309467D01*
X849712Y-310267D01*
X849312Y-311600D01*
X849212Y-312800D01*
X849412Y-314000D01*
X849712Y-314800D01*
X850312Y-315600D01*
X851012Y-316133D01*
X851712Y-316400D01*
X852412D01*
X853112Y-316133D01*
X853712Y-315733D01*
X854212Y-315200D01*
G01X859712Y-308400D02*
X858912Y-308667D01*
X858312Y-309333D01*
X857912Y-310133D01*
X857612Y-311200D01*
X857512Y-312400D01*
X857612Y-313600D01*
X857912Y-314667D01*
X858312Y-315467D01*
X858912Y-316133D01*
X859712Y-316400D01*
X860512Y-316133D01*
X861112Y-315467D01*
X861512Y-314667D01*
X861812Y-313600D01*
X861912Y-312400D01*
X861812Y-311200D01*
X861512Y-310133D01*
X861112Y-309333D01*
X860512Y-308667D01*
X859712Y-308400D01*
G01X799712Y-283400D02*
Y-291400D01*
G01X797412Y-283400D02*
X802012D01*
G01X805812Y-288067D02*
X806512Y-287133D01*
X807112Y-286600D01*
X807912Y-286333D01*
X808612Y-286600D01*
X809112Y-287133D01*
X809512Y-287933D01*
X809612Y-288867D01*
X809512Y-289667D01*
X809112Y-290467D01*
X808512Y-291133D01*
X807812Y-291400D01*
X807012Y-291133D01*
X806312Y-290334D01*
X805912Y-289133D01*
X805812Y-287800D01*
X806012Y-286067D01*
X806312Y-285133D01*
X806812Y-284200D01*
X807512Y-283533D01*
X808212Y-283400D01*
X808912Y-283667D01*
X809412Y-284333D01*
G01X813112Y-291400D02*
Y-283400D01*
X815712Y-290067D01*
X818312Y-283400D01*
Y-291400D01*
G01X820712Y-294067D02*
X826712D01*
G01X831712Y-283400D02*
Y-291400D01*
G01X829412Y-283400D02*
X834012D01*
G01X838312Y-291400D02*
Y-286067D01*
G01Y-287133D02*
X838812Y-286600D01*
X839312Y-286200D01*
X840012Y-286067D01*
X840512Y-286200D01*
X841112Y-286600D01*
G01X849512Y-291400D02*
Y-286067D01*
G01Y-287000D02*
X849112Y-286467D01*
X848512Y-286200D01*
X847812Y-286067D01*
X847112Y-286333D01*
X846512Y-286867D01*
X846112Y-287667D01*
X845912Y-288733D01*
X846112Y-289800D01*
X846512Y-290600D01*
X847112Y-291133D01*
X847812Y-291400D01*
X848512Y-291267D01*
X849112Y-290867D01*
X849512Y-290334D01*
G01X853612Y-293800D02*
X854212Y-294067D01*
X855012Y-293800D01*
X855512Y-293267D01*
X855912Y-292600D01*
X856512Y-290467D01*
X857812Y-286067D01*
G01X854612D02*
X856512Y-290467D01*
G01X860712Y-294067D02*
X866712D01*
G01X872512Y-287133D02*
X872912Y-286733D01*
X873212Y-286067D01*
X873412Y-285133D01*
X873212Y-284333D01*
X872812Y-283800D01*
X872112Y-283400D01*
X869412D01*
Y-291400D01*
X872712D01*
X873412Y-290867D01*
X873812Y-290067D01*
X874012Y-289133D01*
X873812Y-288200D01*
X873212Y-287400D01*
X872512Y-287133D01*
X869412D01*
G01X877712Y-291400D02*
Y-283400D01*
X880112D01*
X880912Y-283800D01*
X881512Y-284733D01*
X881712Y-285800D01*
X881512Y-286867D01*
X881012Y-287667D01*
X880112Y-288067D01*
X877712D01*
G01X896912Y-334067D02*
X896312Y-333667D01*
X895612Y-333400D01*
X894812D01*
X893912Y-333800D01*
X893212Y-334467D01*
X892712Y-335267D01*
X892312Y-336600D01*
X892212Y-337800D01*
X892412Y-339000D01*
X892712Y-339800D01*
X893312Y-340600D01*
X894012Y-341133D01*
X894712Y-341400D01*
X895412D01*
X896112Y-341133D01*
X896712Y-340733D01*
X897212Y-340200D01*
G01X922212Y-341400D02*
Y-333400D01*
X921012Y-335000D01*
G01Y-341400D02*
X923412D01*
G01X928312Y-338067D02*
X929012Y-337133D01*
X929612Y-336600D01*
X930412Y-336333D01*
X931112Y-336600D01*
X931612Y-337133D01*
X932012Y-337933D01*
X932112Y-338867D01*
X932012Y-339667D01*
X931612Y-340467D01*
X931012Y-341133D01*
X930312Y-341400D01*
X929512Y-341133D01*
X928812Y-340334D01*
X928412Y-339133D01*
X928312Y-337800D01*
X928512Y-336067D01*
X928812Y-335133D01*
X929312Y-334200D01*
X930012Y-333533D01*
X930712Y-333400D01*
X931412Y-333667D01*
X931912Y-334333D01*
M02*
